(kicad_pcb
	(version 20260206)
	(generator "pcbnew")
	(generator_version "10.0")
	(general
		(thickness 1.6)
		(legacy_teardrops no)
	)
	(paper "A4")
	(title_block
		(title "04192023_DAF0TMB3IC0_F0TG_MB_C_brd_V02_OCP.brd")
		(comment 1 "Grand Teton / footprints 3482-3486 of 8354")
	)
	(layers
		(0 "F.Cu" signal "TOP")
		(4 "In1.Cu" signal "GND")
		(6 "In2.Cu" signal "IN1")
		(8 "In3.Cu" signal "GND1")
		(10 "In4.Cu" signal "IN2")
		(12 "In5.Cu" signal "GND2")
		(14 "In6.Cu" signal "IN3")
		(16 "In7.Cu" signal "GND3")
		(18 "In8.Cu" signal "VCC")
		(20 "In9.Cu" signal "VCC1")
		(22 "In10.Cu" signal "GND4")
		(24 "In11.Cu" signal "IN4")
		(26 "In12.Cu" signal "GND5")
		(28 "In13.Cu" signal "IN5")
		(30 "In14.Cu" signal "GND6")
		(32 "In15.Cu" signal "IN6")
		(34 "In16.Cu" signal "GND7")
		(2 "B.Cu" signal "BOTTOM")
		(9 "F.Adhes" user "F.Adhesive")
		(11 "B.Adhes" user "B.Adhesive")
		(13 "F.Paste" user "Package Geometry/Pastemask Top")
		(15 "B.Paste" user "Package Geometry/Pastemask Bottom")
		(5 "F.SilkS" user "Ref Des/Silkscreen Top")
		(7 "B.SilkS" user "Ref Des/Silkscreen Bottom")
		(1 "F.Mask" user "Board Geometry/Soldermask Top")
		(3 "B.Mask" user "Board Geometry/Soldermask Bottom")
		(17 "Dwgs.User" user "User.Drawings")
		(19 "Cmts.User" user "User.Comments")
		(21 "Eco1.User" user "User.Eco1")
		(23 "Eco2.User" user "User.Eco2")
		(25 "Edge.Cuts" user "Board Geometry/Outline")
		(27 "Margin" user)
		(31 "F.CrtYd" user "Package Geometry/Place Bound Top")
		(29 "B.CrtYd" user "Package Geometry/Place Bound Bottom")
		(35 "F.Fab" user "Ref Des/Assembly Top")
		(33 "B.Fab" user "Ref Des/Assembly Bottom")
	)
	(footprint ""
		(layer "F.Cu")
		(at 14.82471 -139.25804 -90)
		(property "Reference" "R4080"
			(at 0 0 270)
			(layer "F.SilkS")
			(hide yes)
			(effects
				(font
					(size 1.27 1.27)
				)
			)
		)
		(property "Value" ""
			(at 0 0 270)
			(layer "F.Fab")
			(effects
				(font
					(size 1.27 1.27)
				)
			)
		)
		(duplicate_pad_numbers_are_jumpers no)
		(fp_line
			(start -0.7874 0.4064)
			(end -0.7874 -0.4064)
			(stroke
				(width 0.1524)
				(type default)
			)
			(layer "F.SilkS")
		)
		(fp_line
			(start 0.7874 0.4064)
			(end -0.7874 0.4064)
			(stroke
				(width 0.1524)
				(type default)
			)
			(layer "F.SilkS")
		)
		(fp_line
			(start -0.7874 -0.4064)
			(end 0.7874 -0.4064)
			(stroke
				(width 0.1524)
				(type default)
			)
			(layer "F.SilkS")
		)
		(fp_line
			(start 0.7874 -0.4064)
			(end 0.7874 0.4064)
			(stroke
				(width 0.1524)
				(type default)
			)
			(layer "F.SilkS")
		)
		(fp_line
			(start -0.67945 0.3048)
			(end -0.67945 -0.305054)
			(stroke
				(width 0.1)
				(type default)
			)
			(layer "F.Fab")
		)
		(fp_line
			(start -0.12065 0.3048)
			(end -0.67945 0.3048)
			(stroke
				(width 0.1)
				(type default)
			)
			(layer "F.Fab")
		)
		(fp_line
			(start 0.120396 0.3048)
			(end 0.120396 0.2794)
			(stroke
				(width 0.1)
				(type default)
			)
			(layer "F.Fab")
		)
		(fp_line
			(start 0.67945 0.3048)
			(end 0.120396 0.3048)
			(stroke
				(width 0.1)
				(type default)
			)
			(layer "F.Fab")
		)
		(fp_line
			(start -0.12065 0.2794)
			(end -0.12065 0.3048)
			(stroke
				(width 0.1)
				(type default)
			)
			(layer "F.Fab")
		)
		(fp_line
			(start 0.120396 0.2794)
			(end -0.12065 0.2794)
			(stroke
				(width 0.1)
				(type default)
			)
			(layer "F.Fab")
		)
		(fp_line
			(start -0.12065 -0.2794)
			(end 0.12065 -0.2794)
			(stroke
				(width 0.1)
				(type default)
			)
			(layer "F.Fab")
		)
		(fp_line
			(start 0.12065 -0.2794)
			(end 0.12065 -0.3048)
			(stroke
				(width 0.1)
				(type default)
			)
			(layer "F.Fab")
		)
		(fp_line
			(start 0.12065 -0.3048)
			(end 0.67945 -0.3048)
			(stroke
				(width 0.1)
				(type default)
			)
			(layer "F.Fab")
		)
		(fp_line
			(start 0.67945 -0.3048)
			(end 0.67945 0.3048)
			(stroke
				(width 0.1)
				(type default)
			)
			(layer "F.Fab")
		)
		(fp_line
			(start -0.67945 -0.305054)
			(end -0.12065 -0.305054)
			(stroke
				(width 0.1)
				(type default)
			)
			(layer "F.Fab")
		)
		(fp_line
			(start -0.12065 -0.305054)
			(end -0.12065 -0.2794)
			(stroke
				(width 0.1)
				(type default)
			)
			(layer "F.Fab")
		)
		(pad "1" smd circle
			(at -0.40005 0 270)
			(size 0 0)
			(layers "F.Cu" "F.Mask" "F.Paste")
			(net "P3V3_AUX")
		)
		(pad "2" smd circle
			(at 0.40005 0 270)
			(size 0 0)
			(layers "F.Cu" "F.Mask" "F.Paste")
			(net "P3V3_PWRGD_CLKGEN")
		)
	)
	(footprint ""
		(layer "F.Cu")
		(at 181.648608 -413.786574 90)
		(property "Reference" "R2922"
			(at 0 0 90)
			(layer "F.SilkS")
			(hide yes)
			(effects
				(font
					(size 1.27 1.27)
				)
			)
		)
		(property "Value" ""
			(at 0 0 90)
			(layer "F.Fab")
			(effects
				(font
					(size 1.27 1.27)
				)
			)
		)
		(duplicate_pad_numbers_are_jumpers no)
		(fp_line
			(start 0.7874 -0.4064)
			(end 0.7874 0.4064)
			(stroke
				(width 0.1524)
				(type default)
			)
			(layer "F.SilkS")
		)
		(fp_line
			(start -0.7874 -0.4064)
			(end 0.7874 -0.4064)
			(stroke
				(width 0.1524)
				(type default)
			)
			(layer "F.SilkS")
		)
		(fp_line
			(start 0.7874 0.4064)
			(end -0.7874 0.4064)
			(stroke
				(width 0.1524)
				(type default)
			)
			(layer "F.SilkS")
		)
		(fp_line
			(start -0.7874 0.4064)
			(end -0.7874 -0.4064)
			(stroke
				(width 0.1524)
				(type default)
			)
			(layer "F.SilkS")
		)
		(fp_line
			(start -0.12065 -0.305054)
			(end -0.12065 -0.2794)
			(stroke
				(width 0.1)
				(type default)
			)
			(layer "F.Fab")
		)
		(fp_line
			(start -0.67945 -0.305054)
			(end -0.12065 -0.305054)
			(stroke
				(width 0.1)
				(type default)
			)
			(layer "F.Fab")
		)
		(fp_line
			(start 0.67945 -0.3048)
			(end 0.67945 0.3048)
			(stroke
				(width 0.1)
				(type default)
			)
			(layer "F.Fab")
		)
		(fp_line
			(start 0.12065 -0.3048)
			(end 0.67945 -0.3048)
			(stroke
				(width 0.1)
				(type default)
			)
			(layer "F.Fab")
		)
		(fp_line
			(start 0.12065 -0.2794)
			(end 0.12065 -0.3048)
			(stroke
				(width 0.1)
				(type default)
			)
			(layer "F.Fab")
		)
		(fp_line
			(start -0.12065 -0.2794)
			(end 0.12065 -0.2794)
			(stroke
				(width 0.1)
				(type default)
			)
			(layer "F.Fab")
		)
		(fp_line
			(start 0.120396 0.2794)
			(end -0.12065 0.2794)
			(stroke
				(width 0.1)
				(type default)
			)
			(layer "F.Fab")
		)
		(fp_line
			(start -0.12065 0.2794)
			(end -0.12065 0.3048)
			(stroke
				(width 0.1)
				(type default)
			)
			(layer "F.Fab")
		)
		(fp_line
			(start 0.67945 0.3048)
			(end 0.120396 0.3048)
			(stroke
				(width 0.1)
				(type default)
			)
			(layer "F.Fab")
		)
		(fp_line
			(start 0.120396 0.3048)
			(end 0.120396 0.2794)
			(stroke
				(width 0.1)
				(type default)
			)
			(layer "F.Fab")
		)
		(fp_line
			(start -0.12065 0.3048)
			(end -0.67945 0.3048)
			(stroke
				(width 0.1)
				(type default)
			)
			(layer "F.Fab")
		)
		(fp_line
			(start -0.67945 0.3048)
			(end -0.67945 -0.305054)
			(stroke
				(width 0.1)
				(type default)
			)
			(layer "F.Fab")
		)
		(pad "1" smd circle
			(at -0.40005 0 90)
			(size 0 0)
			(layers "F.Cu" "F.Mask" "F.Paste")
			(net "RST_SMB_SWITCH_N")
		)
		(pad "2" smd circle
			(at 0.40005 0 90)
			(size 0 0)
			(layers "F.Cu" "F.Mask" "F.Paste")
			(net "PU_RST_SMB_U181_N")
		)
	)
	(footprint ""
		(layer "F.Cu")
		(at 356.29596 -257.744976)
		(property "Reference" "C2525"
			(at 0 0 0)
			(layer "F.SilkS")
			(hide yes)
			(effects
				(font
					(size 1.27 1.27)
				)
			)
		)
		(property "Value" ""
			(at 0 0 0)
			(layer "F.Fab")
			(effects
				(font
					(size 1.27 1.27)
				)
			)
		)
		(duplicate_pad_numbers_are_jumpers no)
		(fp_line
			(start -0.7874 -0.4064)
			(end 0.7874 -0.4064)
			(stroke
				(width 0.1524)
				(type default)
			)
			(layer "F.SilkS")
		)
		(fp_line
			(start -0.7874 0.4064)
			(end -0.7874 -0.4064)
			(stroke
				(width 0.1524)
				(type default)
			)
			(layer "F.SilkS")
		)
		(fp_line
			(start 0.7874 -0.4064)
			(end 0.7874 0.4064)
			(stroke
				(width 0.1524)
				(type default)
			)
			(layer "F.SilkS")
		)
		(fp_line
			(start 0.7874 0.4064)
			(end -0.7874 0.4064)
			(stroke
				(width 0.1524)
				(type default)
			)
			(layer "F.SilkS")
		)
		(fp_line
			(start -0.67945 -0.305054)
			(end -0.12065 -0.305054)
			(stroke
				(width 0.1)
				(type default)
			)
			(layer "F.Fab")
		)
		(fp_line
			(start -0.67945 0.3048)
			(end -0.67945 -0.305054)
			(stroke
				(width 0.1)
				(type default)
			)
			(layer "F.Fab")
		)
		(fp_line
			(start -0.12065 -0.305054)
			(end -0.12065 -0.2794)
			(stroke
				(width 0.1)
				(type default)
			)
			(layer "F.Fab")
		)
		(fp_line
			(start -0.12065 -0.2794)
			(end 0.12065 -0.2794)
			(stroke
				(width 0.1)
				(type default)
			)
			(layer "F.Fab")
		)
		(fp_line
			(start -0.12065 0.2794)
			(end -0.12065 0.3048)
			(stroke
				(width 0.1)
				(type default)
			)
			(layer "F.Fab")
		)
		(fp_line
			(start -0.12065 0.3048)
			(end -0.67945 0.3048)
			(stroke
				(width 0.1)
				(type default)
			)
			(layer "F.Fab")
		)
		(fp_line
			(start 0.120396 0.2794)
			(end -0.12065 0.2794)
			(stroke
				(width 0.1)
				(type default)
			)
			(layer "F.Fab")
		)
		(fp_line
			(start 0.120396 0.3048)
			(end 0.120396 0.2794)
			(stroke
				(width 0.1)
				(type default)
			)
			(layer "F.Fab")
		)
		(fp_line
			(start 0.12065 -0.3048)
			(end 0.67945 -0.3048)
			(stroke
				(width 0.1)
				(type default)
			)
			(layer "F.Fab")
		)
		(fp_line
			(start 0.12065 -0.2794)
			(end 0.12065 -0.3048)
			(stroke
				(width 0.1)
				(type default)
			)
			(layer "F.Fab")
		)
		(fp_line
			(start 0.67945 -0.3048)
			(end 0.67945 0.3048)
			(stroke
				(width 0.1)
				(type default)
			)
			(layer "F.Fab")
		)
		(fp_line
			(start 0.67945 0.3048)
			(end 0.120396 0.3048)
			(stroke
				(width 0.1)
				(type default)
			)
			(layer "F.Fab")
		)
		(pad "1" smd circle
			(at -0.40005 0)
			(size 0 0)
			(layers "F.Cu" "F.Mask" "F.Paste")
			(net "PVDD18_S5_P0")
		)
		(pad "2" smd circle
			(at 0.40005 0)
			(size 0 0)
			(layers "F.Cu" "F.Mask" "F.Paste")
			(net "GND")
		)
	)
	(footprint ""
		(layer "F.Cu")
		(at 300.538388 5.082794 180)
		(property "Reference" "J85"
			(at -4.414774 -1.317498 90)
			(unlocked yes)
			(layer "F.SilkS")
			(effects
				(font
					(size 0.7874 0.5842)
					(thickness 0.1524)
				)
				(justify left)
			)
		)
		(property "Value" ""
			(at 0 0 180)
			(layer "F.Fab")
			(effects
				(font
					(size 1.27 1.27)
				)
			)
		)
		(duplicate_pad_numbers_are_jumpers no)
		(fp_line
			(start 1.2192 2.06756)
			(end -1.2192 2.06756)
			(stroke
				(width 0.1524)
				(type default)
			)
			(layer "F.SilkS")
		)
		(fp_line
			(start 1.2192 -2.06756)
			(end 1.2192 2.06756)
			(stroke
				(width 0.1524)
				(type default)
			)
			(layer "F.SilkS")
		)
		(fp_line
			(start -1.2192 2.06756)
			(end -1.2192 -2.06756)
			(stroke
				(width 0.1524)
				(type default)
			)
			(layer "F.SilkS")
		)
		(fp_line
			(start -1.2192 -2.06756)
			(end 1.2192 -2.06756)
			(stroke
				(width 0.1524)
				(type default)
			)
			(layer "F.SilkS")
		)
		(pad "" np_thru_hole circle
			(at -2.8829 -1.27 90)
			(size 1.0414 1.0414)
			(drill 1.0414)
			(layers "*.Cu" "*.Mask")
			(clearance 0.381)
			(thermal_gap 0.381)
		)
		(pad "" np_thru_hole circle
			(at -2.8829 1.27 90)
			(size 1.0414 1.0414)
			(drill 1.0414)
			(layers "*.Cu" "*.Mask")
			(clearance 0.381)
			(thermal_gap 0.381)
		)
		(pad "" np_thru_hole circle
			(at 3.4671 -1.27 90)
			(size 1.0414 1.0414)
			(drill 1.0414)
			(layers "*.Cu" "*.Mask")
			(clearance 0.381)
			(thermal_gap 0.381)
		)
		(pad "" np_thru_hole circle
			(at 3.4671 1.27 90)
			(size 1.0414 1.0414)
			(drill 1.0414)
			(layers "*.Cu" "*.Mask")
			(clearance 0.381)
			(thermal_gap 0.381)
		)
		(pad "1" smd rect
			(at 0.8255 -0.249936 90)
			(size 0.3048 0.508)
			(layers "F.Cu" "F.Mask" "F.Paste")
			(net "DELTA_L_85_10INCH_IN3_DN")
		)
		(pad "2" smd rect
			(at 0.8255 0.249936 90)
			(size 0.3048 0.508)
			(layers "F.Cu" "F.Mask" "F.Paste")
			(net "DELTA_L_85_10INCH_IN3_DP")
		)
		(pad "3" smd circle
			(at 0 0 180)
			(size 0 0)
			(layers "F.Cu" "F.Mask" "F.Paste")
			(net "DELTA_L_GND_1")
		)
		(zone
			(layer "F.Cu")
			(hatch none 0.5)
			(connect_pads
				(clearance 0)
			)
			(min_thickness 0.25)
			(keepout
				(tracks not_allowed)
				(vias allowed)
				(pads allowed)
				(copperpour not_allowed)
				(footprints allowed)
			)
			(placement
				(enabled no)
				(sheetname "")
			)
			(fill
				(thermal_gap 0.5)
				(thermal_bridge_width 0.5)
				(island_removal_mode 0)
			)
			(polygon
				(pts
					(xy 299.420788 5.631434) (xy 299.420788 5.53593) (xy 300.017688 5.53593) (xy 300.017688 5.12953)
					(xy 299.420788 5.12953) (xy 299.420788 5.036058) (xy 300.017688 5.036058) (xy 300.017688 4.629658)
					(xy 299.420788 4.629658) (xy 299.420788 4.534154) (xy 300.119288 4.534154) (xy 300.119288 5.631434)
				)
			)
		)
		(zone
			(layers "F.Cu" "B.Cu" "In1.Cu" "In2.Cu" "In3.Cu" "In4.Cu" "In5.Cu" "In6.Cu"
				"In7.Cu" "In8.Cu" "In9.Cu" "In10.Cu" "In11.Cu" "In12.Cu" "In13.Cu" "In14.Cu"
				"In15.Cu" "In16.Cu"
			)
			(hatch none 0.5)
			(connect_pads
				(clearance 0)
			)
			(min_thickness 0.25)
			(keepout
				(tracks not_allowed)
				(vias allowed)
				(pads allowed)
				(copperpour not_allowed)
				(footprints allowed)
			)
			(placement
				(enabled no)
				(sheetname "")
			)
			(fill
				(thermal_gap 0.5)
				(thermal_bridge_width 0.5)
				(island_removal_mode 0)
			)
			(polygon
				(pts
					(arc
						(start 297.998388 3.812794)
						(mid 296.144188 3.812794)
						(end 297.998388 3.812794)
					)
				)
			)
		)
		(zone
			(layers "F.Cu" "B.Cu" "In1.Cu" "In2.Cu" "In3.Cu" "In4.Cu" "In5.Cu" "In6.Cu"
				"In7.Cu" "In8.Cu" "In9.Cu" "In10.Cu" "In11.Cu" "In12.Cu" "In13.Cu" "In14.Cu"
				"In15.Cu" "In16.Cu"
			)
			(hatch none 0.5)
			(connect_pads
				(clearance 0)
			)
			(min_thickness 0.25)
			(keepout
				(tracks not_allowed)
				(vias allowed)
				(pads allowed)
				(copperpour not_allowed)
				(footprints allowed)
			)
			(placement
				(enabled no)
				(sheetname "")
			)
			(fill
				(thermal_gap 0.5)
				(thermal_bridge_width 0.5)
				(island_removal_mode 0)
			)
			(polygon
				(pts
					(arc
						(start 297.998388 6.352794)
						(mid 296.144188 6.352794)
						(end 297.998388 6.352794)
					)
				)
			)
		)
		(zone
			(layers "F.Cu" "B.Cu" "In1.Cu" "In2.Cu" "In3.Cu" "In4.Cu" "In5.Cu" "In6.Cu"
				"In7.Cu" "In8.Cu" "In9.Cu" "In10.Cu" "In11.Cu" "In12.Cu" "In13.Cu" "In14.Cu"
				"In15.Cu" "In16.Cu"
			)
			(hatch none 0.5)
			(connect_pads
				(clearance 0)
			)
			(min_thickness 0.25)
			(keepout
				(tracks not_allowed)
				(vias allowed)
				(pads allowed)
				(copperpour not_allowed)
				(footprints allowed)
			)
			(placement
				(enabled no)
				(sheetname "")
			)
			(fill
				(thermal_gap 0.5)
				(thermal_bridge_width 0.5)
				(island_removal_mode 0)
			)
			(polygon
				(pts
					(arc
						(start 304.348388 3.812794)
						(mid 302.494188 3.812794)
						(end 304.348388 3.812794)
					)
				)
			)
		)
		(zone
			(layers "F.Cu" "B.Cu" "In1.Cu" "In2.Cu" "In3.Cu" "In4.Cu" "In5.Cu" "In6.Cu"
				"In7.Cu" "In8.Cu" "In9.Cu" "In10.Cu" "In11.Cu" "In12.Cu" "In13.Cu" "In14.Cu"
				"In15.Cu" "In16.Cu"
			)
			(hatch none 0.5)
			(connect_pads
				(clearance 0)
			)
			(min_thickness 0.25)
			(keepout
				(tracks not_allowed)
				(vias allowed)
				(pads allowed)
				(copperpour not_allowed)
				(footprints allowed)
			)
			(placement
				(enabled no)
				(sheetname "")
			)
			(fill
				(thermal_gap 0.5)
				(thermal_bridge_width 0.5)
				(island_removal_mode 0)
			)
			(polygon
				(pts
					(arc
						(start 304.348388 6.352794)
						(mid 302.494188 6.352794)
						(end 304.348388 6.352794)
					)
				)
			)
		)
	)
	(footprint ""
		(layer "F.Cu")
		(at 155.306522 -191.361314 -90)
		(property "Reference" "R3194"
			(at 0 0 270)
			(layer "F.SilkS")
			(hide yes)
			(effects
				(font
					(size 1.27 1.27)
				)
			)
		)
		(property "Value" ""
			(at 0 0 270)
			(layer "F.Fab")
			(effects
				(font
					(size 1.27 1.27)
				)
			)
		)
		(duplicate_pad_numbers_are_jumpers no)
		(fp_line
			(start -0.7874 0.4064)
			(end -0.7874 -0.039878)
			(stroke
				(width 0.1524)
				(type default)
			)
			(layer "F.SilkS")
		)
		(fp_line
			(start 0.7874 0.4064)
			(end -0.7874 0.4064)
			(stroke
				(width 0.1524)
				(type default)
			)
			(layer "F.SilkS")
		)
		(fp_line
			(start 0.7874 -0.065278)
			(end 0.7874 0.4064)
			(stroke
				(width 0.1524)
				(type default)
			)
			(layer "F.SilkS")
		)
		(fp_line
			(start -0.383286 -0.4064)
			(end 0.353314 -0.4064)
			(stroke
				(width 0.1524)
				(type default)
			)
			(layer "F.SilkS")
		)
		(fp_line
			(start -0.67945 0.3048)
			(end -0.67945 -0.305054)
			(stroke
				(width 0.1)
				(type default)
			)
			(layer "F.Fab")
		)
		(fp_line
			(start -0.12065 0.3048)
			(end -0.67945 0.3048)
			(stroke
				(width 0.1)
				(type default)
			)
			(layer "F.Fab")
		)
		(fp_line
			(start 0.120396 0.3048)
			(end 0.120396 0.2794)
			(stroke
				(width 0.1)
				(type default)
			)
			(layer "F.Fab")
		)
		(fp_line
			(start 0.67945 0.3048)
			(end 0.120396 0.3048)
			(stroke
				(width 0.1)
				(type default)
			)
			(layer "F.Fab")
		)
		(fp_line
			(start -0.12065 0.2794)
			(end -0.12065 0.3048)
			(stroke
				(width 0.1)
				(type default)
			)
			(layer "F.Fab")
		)
		(fp_line
			(start 0.120396 0.2794)
			(end -0.12065 0.2794)
			(stroke
				(width 0.1)
				(type default)
			)
			(layer "F.Fab")
		)
		(fp_line
			(start -0.12065 -0.2794)
			(end 0.12065 -0.2794)
			(stroke
				(width 0.1)
				(type default)
			)
			(layer "F.Fab")
		)
		(fp_line
			(start 0.12065 -0.2794)
			(end 0.12065 -0.3048)
			(stroke
				(width 0.1)
				(type default)
			)
			(layer "F.Fab")
		)
		(fp_line
			(start 0.12065 -0.3048)
			(end 0.67945 -0.3048)
			(stroke
				(width 0.1)
				(type default)
			)
			(layer "F.Fab")
		)
		(fp_line
			(start 0.67945 -0.3048)
			(end 0.67945 0.3048)
			(stroke
				(width 0.1)
				(type default)
			)
			(layer "F.Fab")
		)
		(fp_line
			(start -0.67945 -0.305054)
			(end -0.12065 -0.305054)
			(stroke
				(width 0.1)
				(type default)
			)
			(layer "F.Fab")
		)
		(fp_line
			(start -0.12065 -0.305054)
			(end -0.12065 -0.2794)
			(stroke
				(width 0.1)
				(type default)
			)
			(layer "F.Fab")
		)
		(pad "1" smd circle
			(at -0.40005 0 270)
			(size 0 0)
			(layers "F.Cu" "F.Mask" "F.Paste")
			(net "CLK_100M_CPU1_CLK02_R_DP")
		)
		(pad "2" smd circle
			(at 0.40005 0 270)
			(size 0 0)
			(layers "F.Cu" "F.Mask" "F.Paste")
			(net "CLK_100M_CPU1_CLK02_DP")
		)
	)
)
